(kicad_pcb
	(version 20260206)
	(generator "pcbnew")
	(generator_version "10.0")
	(general
		(thickness 1.6)
		(legacy_teardrops no)
	)
	(paper "A4")
	(title_block
		(title "Bryce Canyon_SCC_16316-1_OCP.brd")
		(comment 1 "Bryce Canyon / footprints 720-726 of 1561")
	)
	(layers
		(0 "F.Cu" signal "TOP")
		(4 "In1.Cu" signal "L2GND")
		(6 "In2.Cu" signal "L3")
		(8 "In3.Cu" signal "L4VCC")
		(10 "In4.Cu" signal "L5VCC")
		(12 "In5.Cu" signal "L6")
		(14 "In6.Cu" signal "L7GND")
		(2 "B.Cu" signal "BOTTOM")
		(9 "F.Adhes" user "F.Adhesive")
		(11 "B.Adhes" user "B.Adhesive")
		(13 "F.Paste" user "Package Geometry/Pastemask Top")
		(15 "B.Paste" user "Package Geometry/Pastemask Bottom")
		(5 "F.SilkS" user "Ref Des/Silkscreen Top")
		(7 "B.SilkS" user "Ref Des/Silkscreen Bottom")
		(1 "F.Mask" user "Board Geometry/Soldermask Top")
		(3 "B.Mask" user "Board Geometry/Soldermask Bottom")
		(17 "Dwgs.User" user "User.Drawings")
		(19 "Cmts.User" user "User.Comments")
		(21 "Eco1.User" user "User.Eco1")
		(23 "Eco2.User" user "User.Eco2")
		(25 "Edge.Cuts" user "Board Geometry/Outline")
		(27 "Margin" user)
		(31 "F.CrtYd" user "Package Geometry/Place Bound Top")
		(29 "B.CrtYd" user "Package Geometry/Place Bound Bottom")
		(35 "F.Fab" user "Ref Des/Assembly Top")
		(33 "B.Fab" user "Ref Des/Assembly Bottom")
	)
	(footprint ""
		(layer "F.Cu")
		(at 87.221314 -81.208118 90)
		(property "Reference" "R132"
			(at 0 0 90)
			(layer "F.SilkS")
			(hide yes)
			(effects
				(font
					(size 1.27 1.27)
				)
			)
		)
		(property "Value" "0R2J-2-GP"
			(at 0.064008 -3.993896 90)
			(unlocked yes)
			(layer "F.Fab")
			(hide yes)
			(effects
				(font
					(size 1.016 1.016)
					(thickness 0.1524)
				)
			)
		)
		(property "Device Type" "R402H16"
			(at 0.064008 -5.517896 90)
			(unlocked yes)
			(layer "F.Fab")
			(hide yes)
			(effects
				(font
					(size 1.016 1.016)
					(thickness 0.1524)
				)
			)
		)
		(duplicate_pad_numbers_are_jumpers no)
		(fp_line
			(start 0.508 -0.9398)
			(end -0.508 -0.9398)
			(stroke
				(width 0.1524)
				(type default)
			)
			(layer "F.SilkS")
		)
		(fp_line
			(start -0.508 -0.9398)
			(end -0.508 0.9398)
			(stroke
				(width 0.1524)
				(type default)
			)
			(layer "F.SilkS")
		)
		(fp_rect
			(start -0.508 0.9398)
			(end 0.508 -0.9398)
			(stroke
				(width 0)
				(type default)
			)
			(fill no)
			(layer "F.CrtYd")
		)
		(fp_rect
			(start -0.508 0.9398)
			(end 0.508 -0.9398)
			(stroke
				(width 0)
				(type default)
			)
			(fill no)
			(layer "F.Fab")
		)
		(pad "1" smd custom
			(at 0 -0.4445 90)
			(size 0.1397 0.1397)
			(layers "F.Cu" "F.Mask" "F.Paste")
			(net "P0V9_PG")
			(options
				(clearance outline)
				(anchor circle)
			)
			(primitives
				(gr_poly
					(pts
						(arc
							(start -0.1778 -0.2794)
							(mid -0.249642 -0.249642)
							(end -0.2794 -0.1778)
						)
						(arc
							(start -0.2794 0.1778)
							(mid -0.249642 0.249642)
							(end -0.1778 0.2794)
						)
						(arc
							(start 0.1778 0.2794)
							(mid 0.249642 0.249642)
							(end 0.2794 0.1778)
						)
						(arc
							(start 0.2794 -0.1778)
							(mid 0.249642 -0.249642)
							(end 0.1778 -0.2794)
						)
					)
					(width 0)
					(fill yes)
				)
			)
		)
		(pad "2" smd custom
			(at 0 0.4445 90)
			(size 0.1397 0.1397)
			(layers "F.Cu" "F.Mask" "F.Paste")
			(net "RESET_MR#")
			(options
				(clearance outline)
				(anchor circle)
			)
			(primitives
				(gr_poly
					(pts
						(arc
							(start -0.1778 -0.2794)
							(mid -0.249642 -0.249642)
							(end -0.2794 -0.1778)
						)
						(arc
							(start -0.2794 0.1778)
							(mid -0.249642 0.249642)
							(end -0.1778 0.2794)
						)
						(arc
							(start 0.1778 0.2794)
							(mid 0.249642 0.249642)
							(end 0.2794 0.1778)
						)
						(arc
							(start 0.2794 -0.1778)
							(mid 0.249642 -0.249642)
							(end 0.1778 -0.2794)
						)
					)
					(width 0)
					(fill yes)
				)
			)
		)
	)
	(footprint ""
		(layer "F.Cu")
		(at 164.52088 -100.4062 -90)
		(property "Reference" "R486"
			(at 0 0 270)
			(layer "F.SilkS")
			(hide yes)
			(effects
				(font
					(size 1.27 1.27)
				)
			)
		)
		(property "Value" "0R2J-2-GP"
			(at 0.064008 -3.993896 270)
			(unlocked yes)
			(layer "F.Fab")
			(hide yes)
			(effects
				(font
					(size 1.016 1.016)
					(thickness 0.1524)
				)
			)
		)
		(property "Device Type" "R402H16"
			(at 0.064008 -5.517896 270)
			(unlocked yes)
			(layer "F.Fab")
			(hide yes)
			(effects
				(font
					(size 1.016 1.016)
					(thickness 0.1524)
				)
			)
		)
		(duplicate_pad_numbers_are_jumpers no)
		(fp_line
			(start -0.508 -0.9398)
			(end -0.508 0.9398)
			(stroke
				(width 0.1524)
				(type default)
			)
			(layer "F.SilkS")
		)
		(fp_line
			(start 0.508 -0.9398)
			(end -0.508 -0.9398)
			(stroke
				(width 0.1524)
				(type default)
			)
			(layer "F.SilkS")
		)
		(fp_rect
			(start -0.508 0.9398)
			(end 0.508 -0.9398)
			(stroke
				(width 0)
				(type default)
			)
			(fill no)
			(layer "F.CrtYd")
		)
		(fp_rect
			(start -0.508 0.9398)
			(end 0.508 -0.9398)
			(stroke
				(width 0)
				(type default)
			)
			(fill no)
			(layer "F.Fab")
		)
		(pad "1" smd custom
			(at 0 -0.4445 270)
			(size 0.1397 0.1397)
			(layers "F.Cu" "F.Mask" "F.Paste")
			(net "VT235_EN")
			(options
				(clearance outline)
				(anchor circle)
			)
			(primitives
				(gr_poly
					(pts
						(arc
							(start -0.1778 -0.2794)
							(mid -0.249642 -0.249642)
							(end -0.2794 -0.1778)
						)
						(arc
							(start -0.2794 0.1778)
							(mid -0.249642 0.249642)
							(end -0.1778 0.2794)
						)
						(arc
							(start 0.1778 0.2794)
							(mid 0.249642 0.249642)
							(end 0.2794 0.1778)
						)
						(arc
							(start 0.2794 -0.1778)
							(mid 0.249642 -0.249642)
							(end 0.1778 -0.2794)
						)
					)
					(width 0)
					(fill yes)
				)
			)
		)
		(pad "2" smd custom
			(at 0 0.4445 270)
			(size 0.1397 0.1397)
			(layers "F.Cu" "F.Mask" "F.Paste")
			(net "P1V5_C_PG")
			(options
				(clearance outline)
				(anchor circle)
			)
			(primitives
				(gr_poly
					(pts
						(arc
							(start -0.1778 -0.2794)
							(mid -0.249642 -0.249642)
							(end -0.2794 -0.1778)
						)
						(arc
							(start -0.2794 0.1778)
							(mid -0.249642 0.249642)
							(end -0.1778 0.2794)
						)
						(arc
							(start 0.1778 0.2794)
							(mid 0.249642 0.249642)
							(end 0.2794 0.1778)
						)
						(arc
							(start 0.2794 -0.1778)
							(mid 0.249642 -0.249642)
							(end 0.1778 -0.2794)
						)
					)
					(width 0)
					(fill yes)
				)
			)
		)
	)
	(footprint ""
		(layer "F.Cu")
		(at 158.64078 -93.80728 90)
		(property "Reference" "C504"
			(at 0 0 90)
			(layer "F.SilkS")
			(hide yes)
			(effects
				(font
					(size 1.27 1.27)
				)
			)
		)
		(property "Value" "SCD1U16V2KX-3GP"
			(at 1.1811 -2.7051 90)
			(unlocked yes)
			(layer "F.Fab")
			(hide yes)
			(effects
				(font
					(size 1.016 1.016)
					(thickness 0.1524)
				)
			)
		)
		(property "Device Type" "C402H22"
			(at 1.1811 -4.2291 90)
			(unlocked yes)
			(layer "F.Fab")
			(hide yes)
			(effects
				(font
					(size 1.016 1.016)
					(thickness 0.1524)
				)
			)
		)
		(duplicate_pad_numbers_are_jumpers no)
		(fp_rect
			(start -0.4318 0.9525)
			(end 0.4318 -0.9525)
			(stroke
				(width 0)
				(type default)
			)
			(fill no)
			(layer "F.CrtYd")
		)
		(fp_rect
			(start -0.4318 0.9525)
			(end 0.4318 -0.9525)
			(stroke
				(width 0)
				(type default)
			)
			(fill no)
			(layer "F.Fab")
		)
		(pad "1" smd custom
			(at 0 -0.4445 90)
			(size 0.1524 0.1524)
			(layers "F.Cu" "F.Mask" "F.Paste")
			(net "P3V3")
			(options
				(clearance outline)
				(anchor circle)
			)
			(primitives
				(gr_poly
					(pts
						(arc
							(start 0.3048 -0.2032)
							(mid 0.275042 -0.275042)
							(end 0.2032 -0.3048)
						)
						(arc
							(start -0.2032 -0.3048)
							(mid -0.275042 -0.275042)
							(end -0.3048 -0.2032)
						)
						(arc
							(start -0.3048 0.2032)
							(mid -0.275042 0.275042)
							(end -0.2032 0.3048)
						)
						(arc
							(start 0.2032 0.3048)
							(mid 0.275042 0.275042)
							(end 0.3048 0.2032)
						)
					)
					(width 0)
					(fill yes)
				)
			)
		)
		(pad "2" smd custom
			(at 0 0.4445 90)
			(size 0.1524 0.1524)
			(layers "F.Cu" "F.Mask" "F.Paste")
			(net "GND")
			(options
				(clearance outline)
				(anchor circle)
			)
			(primitives
				(gr_poly
					(pts
						(arc
							(start 0.3048 -0.2032)
							(mid 0.275042 -0.275042)
							(end 0.2032 -0.3048)
						)
						(arc
							(start -0.2032 -0.3048)
							(mid -0.275042 -0.275042)
							(end -0.3048 -0.2032)
						)
						(arc
							(start -0.3048 0.2032)
							(mid -0.275042 0.275042)
							(end -0.2032 0.3048)
						)
						(arc
							(start 0.2032 0.3048)
							(mid 0.275042 0.275042)
							(end 0.3048 0.2032)
						)
					)
					(width 0)
					(fill yes)
				)
			)
		)
	)
	(footprint ""
		(layer "F.Cu")
		(at 70.866 -103.505 180)
		(property "Reference" "C642"
			(at 0 0 180)
			(layer "F.SilkS")
			(hide yes)
			(effects
				(font
					(size 1.27 1.27)
				)
			)
		)
		(property "Value" "SC68P50V2JN-2-GP"
			(at 1.1811 -2.7051 180)
			(unlocked yes)
			(layer "F.Fab")
			(hide yes)
			(effects
				(font
					(size 1.016 1.016)
					(thickness 0.1524)
				)
			)
		)
		(property "Device Type" "C402H22"
			(at 1.1811 -4.2291 180)
			(unlocked yes)
			(layer "F.Fab")
			(hide yes)
			(effects
				(font
					(size 1.016 1.016)
					(thickness 0.1524)
				)
			)
		)
		(duplicate_pad_numbers_are_jumpers no)
		(fp_rect
			(start -0.4318 0.9525)
			(end 0.4318 -0.9525)
			(stroke
				(width 0)
				(type default)
			)
			(fill no)
			(layer "F.CrtYd")
		)
		(fp_rect
			(start -0.4318 0.9525)
			(end 0.4318 -0.9525)
			(stroke
				(width 0)
				(type default)
			)
			(fill no)
			(layer "F.Fab")
		)
		(pad "1" smd custom
			(at 0 -0.4445 180)
			(size 0.1524 0.1524)
			(layers "F.Cu" "F.Mask" "F.Paste")
			(net "P3V3_VFB")
			(options
				(clearance outline)
				(anchor circle)
			)
			(primitives
				(gr_poly
					(pts
						(arc
							(start 0.3048 -0.2032)
							(mid 0.275042 -0.275042)
							(end 0.2032 -0.3048)
						)
						(arc
							(start -0.2032 -0.3048)
							(mid -0.275042 -0.275042)
							(end -0.3048 -0.2032)
						)
						(arc
							(start -0.3048 0.2032)
							(mid -0.275042 0.275042)
							(end -0.2032 0.3048)
						)
						(arc
							(start 0.2032 0.3048)
							(mid 0.275042 0.275042)
							(end 0.3048 0.2032)
						)
					)
					(width 0)
					(fill yes)
				)
			)
		)
		(pad "2" smd custom
			(at 0 0.4445 180)
			(size 0.1524 0.1524)
			(layers "F.Cu" "F.Mask" "F.Paste")
			(net "P3V3_VFB_R")
			(options
				(clearance outline)
				(anchor circle)
			)
			(primitives
				(gr_poly
					(pts
						(arc
							(start 0.3048 -0.2032)
							(mid 0.275042 -0.275042)
							(end 0.2032 -0.3048)
						)
						(arc
							(start -0.2032 -0.3048)
							(mid -0.275042 -0.275042)
							(end -0.3048 -0.2032)
						)
						(arc
							(start -0.3048 0.2032)
							(mid -0.275042 0.275042)
							(end -0.2032 0.3048)
						)
						(arc
							(start 0.2032 0.3048)
							(mid 0.275042 0.275042)
							(end 0.3048 0.2032)
						)
					)
					(width 0)
					(fill yes)
				)
			)
		)
	)
	(footprint ""
		(layer "F.Cu")
		(at 19.6088 -93.6752)
		(property "Reference" "R409"
			(at 0 0 0)
			(layer "F.SilkS")
			(hide yes)
			(effects
				(font
					(size 1.27 1.27)
				)
			)
		)
		(property "Value" "1KR2F-3-GP"
			(at 0.064008 -3.993896 0)
			(unlocked yes)
			(layer "F.Fab")
			(hide yes)
			(effects
				(font
					(size 1.016 1.016)
					(thickness 0.1524)
				)
			)
		)
		(property "Device Type" "R402H16"
			(at 0.064008 -5.517896 0)
			(unlocked yes)
			(layer "F.Fab")
			(hide yes)
			(effects
				(font
					(size 1.016 1.016)
					(thickness 0.1524)
				)
			)
		)
		(duplicate_pad_numbers_are_jumpers no)
		(fp_line
			(start -0.508 -0.9398)
			(end -0.508 0.9398)
			(stroke
				(width 0.1524)
				(type default)
			)
			(layer "F.SilkS")
		)
		(fp_line
			(start 0.508 -0.9398)
			(end -0.508 -0.9398)
			(stroke
				(width 0.1524)
				(type default)
			)
			(layer "F.SilkS")
		)
		(fp_rect
			(start -0.508 0.9398)
			(end 0.508 -0.9398)
			(stroke
				(width 0)
				(type default)
			)
			(fill no)
			(layer "F.CrtYd")
		)
		(fp_rect
			(start -0.508 0.9398)
			(end 0.508 -0.9398)
			(stroke
				(width 0)
				(type default)
			)
			(fill no)
			(layer "F.Fab")
		)
		(pad "1" smd custom
			(at 0 -0.4445)
			(size 0.1397 0.1397)
			(layers "F.Cu" "F.Mask" "F.Paste")
			(net "P3V3")
			(options
				(clearance outline)
				(anchor circle)
			)
			(primitives
				(gr_poly
					(pts
						(arc
							(start -0.1778 -0.2794)
							(mid -0.249642 -0.249642)
							(end -0.2794 -0.1778)
						)
						(arc
							(start -0.2794 0.1778)
							(mid -0.249642 0.249642)
							(end -0.1778 0.2794)
						)
						(arc
							(start 0.1778 0.2794)
							(mid 0.249642 0.249642)
							(end 0.2794 0.1778)
						)
						(arc
							(start 0.2794 -0.1778)
							(mid 0.249642 -0.249642)
							(end 0.1778 -0.2794)
						)
					)
					(width 0)
					(fill yes)
				)
			)
		)
		(pad "2" smd custom
			(at 0 0.4445)
			(size 0.1397 0.1397)
			(layers "F.Cu" "F.Mask" "F.Paste")
			(net "I2C_BMC_LOC_SCL0")
			(options
				(clearance outline)
				(anchor circle)
			)
			(primitives
				(gr_poly
					(pts
						(arc
							(start -0.1778 -0.2794)
							(mid -0.249642 -0.249642)
							(end -0.2794 -0.1778)
						)
						(arc
							(start -0.2794 0.1778)
							(mid -0.249642 0.249642)
							(end -0.1778 0.2794)
						)
						(arc
							(start 0.1778 0.2794)
							(mid 0.249642 0.249642)
							(end 0.2794 0.1778)
						)
						(arc
							(start 0.2794 -0.1778)
							(mid 0.249642 -0.249642)
							(end 0.1778 -0.2794)
						)
					)
					(width 0)
					(fill yes)
				)
			)
		)
	)
	(footprint ""
		(layer "F.Cu")
		(at 185.3946 -117.8306 -90)
		(property "Reference" "C692"
			(at 0 0 270)
			(layer "F.SilkS")
			(hide yes)
			(effects
				(font
					(size 1.27 1.27)
				)
			)
		)
		(property "Value" "SCD1U16V2KX-3GP"
			(at 1.1811 -2.7051 270)
			(unlocked yes)
			(layer "F.Fab")
			(hide yes)
			(effects
				(font
					(size 1.016 1.016)
					(thickness 0.1524)
				)
			)
		)
		(property "Device Type" "C402H22"
			(at 1.1811 -4.2291 270)
			(unlocked yes)
			(layer "F.Fab")
			(hide yes)
			(effects
				(font
					(size 1.016 1.016)
					(thickness 0.1524)
				)
			)
		)
		(duplicate_pad_numbers_are_jumpers no)
		(fp_rect
			(start -0.4318 0.9525)
			(end 0.4318 -0.9525)
			(stroke
				(width 0)
				(type default)
			)
			(fill no)
			(layer "F.CrtYd")
		)
		(fp_rect
			(start -0.4318 0.9525)
			(end 0.4318 -0.9525)
			(stroke
				(width 0)
				(type default)
			)
			(fill no)
			(layer "F.Fab")
		)
		(pad "1" smd custom
			(at 0 -0.4445 270)
			(size 0.1524 0.1524)
			(layers "F.Cu" "F.Mask" "F.Paste")
			(net "P1V8_C")
			(options
				(clearance outline)
				(anchor circle)
			)
			(primitives
				(gr_poly
					(pts
						(arc
							(start 0.3048 -0.2032)
							(mid 0.275042 -0.275042)
							(end 0.2032 -0.3048)
						)
						(arc
							(start -0.2032 -0.3048)
							(mid -0.275042 -0.275042)
							(end -0.3048 -0.2032)
						)
						(arc
							(start -0.3048 0.2032)
							(mid -0.275042 0.275042)
							(end -0.2032 0.3048)
						)
						(arc
							(start 0.2032 0.3048)
							(mid 0.275042 0.275042)
							(end 0.3048 0.2032)
						)
					)
					(width 0)
					(fill yes)
				)
			)
		)
		(pad "2" smd custom
			(at 0 0.4445 270)
			(size 0.1524 0.1524)
			(layers "F.Cu" "F.Mask" "F.Paste")
			(net "GND")
			(options
				(clearance outline)
				(anchor circle)
			)
			(primitives
				(gr_poly
					(pts
						(arc
							(start 0.3048 -0.2032)
							(mid 0.275042 -0.275042)
							(end 0.2032 -0.3048)
						)
						(arc
							(start -0.2032 -0.3048)
							(mid -0.275042 -0.275042)
							(end -0.3048 -0.2032)
						)
						(arc
							(start -0.3048 0.2032)
							(mid -0.275042 0.275042)
							(end -0.2032 0.3048)
						)
						(arc
							(start 0.2032 0.3048)
							(mid 0.275042 0.275042)
							(end 0.3048 0.2032)
						)
					)
					(width 0)
					(fill yes)
				)
			)
		)
	)
	(footprint ""
		(layer "F.Cu")
		(at 167.28694 -58.08345)
		(property "Reference" "R265"
			(at 0 0 0)
			(layer "F.SilkS")
			(hide yes)
			(effects
				(font
					(size 1.27 1.27)
				)
			)
		)
		(property "Value" "4K7R2F-GP"
			(at 0.064008 -3.993896 0)
			(unlocked yes)
			(layer "F.Fab")
			(hide yes)
			(effects
				(font
					(size 1.016 1.016)
					(thickness 0.1524)
				)
			)
		)
		(property "Device Type" "R402H16"
			(at 0.064008 -5.517896 0)
			(unlocked yes)
			(layer "F.Fab")
			(hide yes)
			(effects
				(font
					(size 1.016 1.016)
					(thickness 0.1524)
				)
			)
		)
		(duplicate_pad_numbers_are_jumpers no)
		(fp_line
			(start -0.508 -0.9398)
			(end -0.508 0.9398)
			(stroke
				(width 0.1524)
				(type default)
			)
			(layer "F.SilkS")
		)
		(fp_line
			(start 0.508 -0.9398)
			(end -0.508 -0.9398)
			(stroke
				(width 0.1524)
				(type default)
			)
			(layer "F.SilkS")
		)
		(fp_rect
			(start -0.508 0.9398)
			(end 0.508 -0.9398)
			(stroke
				(width 0)
				(type default)
			)
			(fill no)
			(layer "F.CrtYd")
		)
		(fp_rect
			(start -0.508 0.9398)
			(end 0.508 -0.9398)
			(stroke
				(width 0)
				(type default)
			)
			(fill no)
			(layer "F.Fab")
		)
		(pad "1" smd custom
			(at 0 -0.4445)
			(size 0.1397 0.1397)
			(layers "F.Cu" "F.Mask" "F.Paste")
			(net "P1V8_C")
			(options
				(clearance outline)
				(anchor circle)
			)
			(primitives
				(gr_poly
					(pts
						(arc
							(start -0.1778 -0.2794)
							(mid -0.249642 -0.249642)
							(end -0.2794 -0.1778)
						)
						(arc
							(start -0.2794 0.1778)
							(mid -0.249642 0.249642)
							(end -0.1778 0.2794)
						)
						(arc
							(start 0.1778 0.2794)
							(mid 0.249642 0.249642)
							(end 0.2794 0.1778)
						)
						(arc
							(start 0.2794 -0.1778)
							(mid 0.249642 -0.249642)
							(end 0.1778 -0.2794)
						)
					)
					(width 0)
					(fill yes)
				)
			)
		)
		(pad "2" smd custom
			(at 0 0.4445)
			(size 0.1397 0.1397)
			(layers "F.Cu" "F.Mask" "F.Paste")
			(net "ICE0_TDI")
			(options
				(clearance outline)
				(anchor circle)
			)
			(primitives
				(gr_poly
					(pts
						(arc
							(start -0.1778 -0.2794)
							(mid -0.249642 -0.249642)
							(end -0.2794 -0.1778)
						)
						(arc
							(start -0.2794 0.1778)
							(mid -0.249642 0.249642)
							(end -0.1778 0.2794)
						)
						(arc
							(start 0.1778 0.2794)
							(mid 0.249642 0.249642)
							(end 0.2794 0.1778)
						)
						(arc
							(start 0.2794 -0.1778)
							(mid 0.249642 -0.249642)
							(end 0.1778 -0.2794)
						)
					)
					(width 0)
					(fill yes)
				)
			)
		)
	)
)
